# BASEBOARD_FAB2 (Tioga Pass) — schematic netlist excerpt (pin names and nets, part order shuffled) for the footprints in the layout excerpt that follows; sources: Cadence DE-HDL packaged netlist, KiCad conversion of Wiwynn_Tioga_Pass_MB.brd

R25W45  120R2F-GP  1%  pkg RCL_GP  page 151 : \1\ = BMC_M_A7 ; \2\ = P1V2_AUX_BMC
R7D2  RES  1.00K 1% CHIP  pkg 0402  page 133 : A = P3V3_STBY ; B = PU_FM_RCIN_N
R4G18  RES  10.0K 1% CHIP  pkg 0402  page 221 : A = P3V3 ; B = PWRGD_PVTT_ABC_CPU0_R

(kicad_pcb
	(version 20260206)
	(generator "pcbnew")
	(generator_version "10.0")
	(general
		(thickness 1.6)
		(legacy_teardrops no)
	)
	(paper "A4")
	(title_block
		(title "Wiwynn_Tioga_Pass_MB.brd")
		(comment 1 "Tioga Pass / footprints 2118-2120 of 4770")
	)
	(layers
		(0 "F.Cu" signal "TOP")
		(4 "In1.Cu" signal "L2GND")
		(6 "In2.Cu" signal "L3")
		(8 "In3.Cu" signal "L4GND")
		(10 "In4.Cu" signal "L5")
		(12 "In5.Cu" signal "L6GND")
		(14 "In6.Cu" signal "L7VCC")
		(16 "In7.Cu" signal "L8VCC")
		(18 "In8.Cu" signal "L9GND")
		(20 "In9.Cu" signal "L10")
		(22 "In10.Cu" signal "L11GND")
		(24 "In11.Cu" signal "L12")
		(26 "In12.Cu" signal "L13GND")
		(2 "B.Cu" signal "BOTTOM")
		(9 "F.Adhes" user "F.Adhesive")
		(11 "B.Adhes" user "B.Adhesive")
		(13 "F.Paste" user "Package Geometry/Pastemask Top")
		(15 "B.Paste" user "Package Geometry/Pastemask Bottom")
		(5 "F.SilkS" user "Ref Des/Silkscreen Top")
		(7 "B.SilkS" user "Ref Des/Silkscreen Bottom")
		(1 "F.Mask" user "Board Geometry/Soldermask Top")
		(3 "B.Mask" user "Board Geometry/Soldermask Bottom")
		(17 "Dwgs.User" user "User.Drawings")
		(19 "Cmts.User" user "User.Comments")
		(21 "Eco1.User" user "User.Eco1")
		(23 "Eco2.User" user "User.Eco2")
		(25 "Edge.Cuts" user "Board Geometry/Outline")
		(27 "Margin" user)
		(31 "F.CrtYd" user "Package Geometry/Place Bound Top")
		(29 "B.CrtYd" user "Package Geometry/Place Bound Bottom")
		(35 "F.Fab" user "Ref Des/Assembly Top")
		(33 "B.Fab" user "Ref Des/Assembly Bottom")
	)
	(footprint ""
		(layer "F.Cu")
		(at 436.547006 -43.556174 180)
		(property "Reference" "R25W45"
			(at 0 0 180)
			(layer "F.SilkS")
			(hide yes)
			(effects
				(font
					(size 1.27 1.27)
				)
			)
		)
		(property "Value" "*"
			(at 0.064008 -4.108196 180)
			(unlocked yes)
			(layer "F.Fab")
			(hide yes)
			(effects
				(font
					(size 1.27 1.016)
					(thickness 0.1524)
				)
			)
		)
		(property "Device Type" "120R2F-GP_RCL_GP-120R2F-GP,64.A"
			(at 0.064008 -5.632196 180)
			(unlocked yes)
			(layer "F.Fab")
			(hide yes)
			(effects
				(font
					(size 1.27 1.016)
					(thickness 0.1524)
				)
			)
		)
		(duplicate_pad_numbers_are_jumpers no)
		(fp_line
			(start 0.508 -0.9398)
			(end -0.508 -0.9398)
			(stroke
				(width 0.1524)
				(type default)
			)
			(layer "F.SilkS")
		)
		(fp_line
			(start -0.508 -0.9398)
			(end -0.508 0.9398)
			(stroke
				(width 0.1524)
				(type default)
			)
			(layer "F.SilkS")
		)
		(fp_rect
			(start -0.508 0.9398)
			(end 0.508 -0.9398)
			(stroke
				(width 0)
				(type default)
			)
			(fill no)
			(layer "F.CrtYd")
		)
		(fp_rect
			(start -0.508 0.9398)
			(end 0.508 -0.9398)
			(stroke
				(width 0)
				(type default)
			)
			(fill no)
			(layer "F.Fab")
		)
		(pad "1" smd custom
			(at 0 -0.4445 180)
			(size 0.1397 0.1397)
			(layers "F.Cu" "F.Mask" "F.Paste")
			(net "BMC_M_A7")
			(options
				(clearance outline)
				(anchor circle)
			)
			(primitives
				(gr_poly
					(pts
						(arc
							(start -0.1778 -0.2794)
							(mid -0.249642 -0.249642)
							(end -0.2794 -0.1778)
						)
						(arc
							(start -0.2794 0.1778)
							(mid -0.249642 0.249642)
							(end -0.1778 0.2794)
						)
						(arc
							(start 0.1778 0.2794)
							(mid 0.249642 0.249642)
							(end 0.2794 0.1778)
						)
						(arc
							(start 0.2794 -0.1778)
							(mid 0.249642 -0.249642)
							(end 0.1778 -0.2794)
						)
					)
					(width 0)
					(fill yes)
				)
			)
		)
		(pad "2" smd custom
			(at 0 0.4445 180)
			(size 0.1397 0.1397)
			(layers "F.Cu" "F.Mask" "F.Paste")
			(net "P1V2_AUX_BMC")
			(options
				(clearance outline)
				(anchor circle)
			)
			(primitives
				(gr_poly
					(pts
						(arc
							(start -0.1778 -0.2794)
							(mid -0.249642 -0.249642)
							(end -0.2794 -0.1778)
						)
						(arc
							(start -0.2794 0.1778)
							(mid -0.249642 0.249642)
							(end -0.1778 0.2794)
						)
						(arc
							(start 0.1778 0.2794)
							(mid 0.249642 0.249642)
							(end 0.2794 0.1778)
						)
						(arc
							(start 0.2794 -0.1778)
							(mid 0.249642 -0.249642)
							(end 0.1778 -0.2794)
						)
					)
					(width 0)
					(fill yes)
				)
			)
		)
	)
	(footprint ""
		(layer "F.Cu")
		(at 180.975 -5.334)
		(property "Reference" "R4G18"
			(at 0 0 0)
			(layer "F.SilkS")
			(hide yes)
			(effects
				(font
					(size 1.27 1.27)
				)
			)
		)
		(property "Value" ""
			(at 0 0 0)
			(layer "F.Fab")
			(effects
				(font
					(size 1.27 1.27)
				)
			)
		)
		(duplicate_pad_numbers_are_jumpers no)
		(fp_rect
			(start 0.2794 0.9906)
			(end -0.2794 -0.1016)
			(stroke
				(width 0)
				(type default)
			)
			(fill no)
			(layer "F.CrtYd")
		)
		(fp_line
			(start -0.2794 -0.1016)
			(end -0.2794 0.9906)
			(stroke
				(width 0.1)
				(type default)
			)
			(layer "F.Fab")
		)
		(fp_line
			(start -0.2794 0.9906)
			(end 0.2794 0.9906)
			(stroke
				(width 0.1)
				(type default)
			)
			(layer "F.Fab")
		)
		(fp_line
			(start 0.2794 -0.1016)
			(end -0.2794 -0.1016)
			(stroke
				(width 0.1)
				(type default)
			)
			(layer "F.Fab")
		)
		(fp_line
			(start 0.2794 0.9906)
			(end 0.2794 -0.1016)
			(stroke
				(width 0.1)
				(type default)
			)
			(layer "F.Fab")
		)
		(pad "1" smd rect
			(at 0 0)
			(size 0.508 0.508)
			(layers "F.Cu" "F.Mask" "F.Paste")
			(net "P3V3")
		)
		(pad "2" smd rect
			(at 0 0.889)
			(size 0.508 0.508)
			(layers "F.Cu" "F.Mask" "F.Paste")
			(net "PWRGD_PVTT_ABC_CPU0_R")
		)
		(zone
			(layer "F.Cu")
			(hatch none 0.5)
			(connect_pads
				(clearance 0)
			)
			(min_thickness 0.25)
			(keepout
				(tracks not_allowed)
				(vias allowed)
				(pads allowed)
				(copperpour not_allowed)
				(footprints allowed)
			)
			(placement
				(enabled no)
				(sheetname "")
			)
			(fill
				(thermal_gap 0.5)
				(thermal_bridge_width 0.5)
				(island_removal_mode 0)
			)
			(polygon
				(pts
					(xy 181.229 -4.699) (xy 181.229 -5.08) (xy 180.721 -5.08) (xy 180.721 -4.699)
				)
			)
		)
		(zone
			(layer "F.Cu")
			(hatch none 0.5)
			(connect_pads
				(clearance 0)
			)
			(min_thickness 0.25)
			(keepout
				(tracks allowed)
				(vias not_allowed)
				(pads allowed)
				(copperpour not_allowed)
				(footprints allowed)
			)
			(placement
				(enabled no)
				(sheetname "")
			)
			(fill
				(thermal_gap 0.5)
				(thermal_bridge_width 0.5)
				(island_removal_mode 0)
			)
			(polygon
				(pts
					(xy 181.229 -4.699) (xy 181.229 -5.08) (xy 180.721 -5.08) (xy 180.721 -4.699)
				)
			)
		)
	)
	(footprint ""
		(layer "F.Cu")
		(at 378.46 -87.3125 180)
		(property "Reference" "R7D2"
			(at 0 0 180)
			(layer "F.SilkS")
			(hide yes)
			(effects
				(font
					(size 1.27 1.27)
				)
			)
		)
		(property "Value" ""
			(at 0 0 180)
			(layer "F.Fab")
			(effects
				(font
					(size 1.27 1.27)
				)
			)
		)
		(duplicate_pad_numbers_are_jumpers no)
		(fp_poly
			(pts
				(xy -0.2794 -0.1016) (xy 0.2794 -0.1016) (xy 0.2794 0.9906) (xy -0.2794 0.9906)
			)
			(stroke
				(width 0)
				(type default)
			)
			(fill no)
			(layer "F.CrtYd")
		)
		(fp_line
			(start 0.2794 0.9906)
			(end 0.2794 -0.1016)
			(stroke
				(width 0.1)
				(type default)
			)
			(layer "F.Fab")
		)
		(fp_line
			(start 0.2794 -0.1016)
			(end -0.2794 -0.1016)
			(stroke
				(width 0.1)
				(type default)
			)
			(layer "F.Fab")
		)
		(fp_line
			(start -0.2794 0.9906)
			(end 0.2794 0.9906)
			(stroke
				(width 0.1)
				(type default)
			)
			(layer "F.Fab")
		)
		(fp_line
			(start -0.2794 -0.1016)
			(end -0.2794 0.9906)
			(stroke
				(width 0.1)
				(type default)
			)
			(layer "F.Fab")
		)
		(pad "1" smd rect
			(at 0 0 180)
			(size 0.508 0.508)
			(layers "F.Cu" "F.Mask" "F.Paste")
			(net "P3V3_STBY")
		)
		(pad "2" smd rect
			(at 0 0.889 180)
			(size 0.508 0.508)
			(layers "F.Cu" "F.Mask" "F.Paste")
			(net "PU_FM_RCIN_N")
		)
		(zone
			(layer "F.Cu")
			(hatch none 0.5)
			(connect_pads
				(clearance 0)
			)
			(min_thickness 0.25)
			(keepout
				(tracks not_allowed)
				(vias allowed)
				(pads allowed)
				(copperpour not_allowed)
				(footprints allowed)
			)
			(placement
				(enabled no)
				(sheetname "")
			)
			(fill
				(thermal_gap 0.5)
				(thermal_bridge_width 0.5)
				(island_removal_mode 0)
			)
			(polygon
				(pts
					(xy 378.714 -87.9475) (xy 378.206 -87.9475) (xy 378.206 -87.5665) (xy 378.714 -87.5665)
				)
			)
		)
		(zone
			(layer "F.Cu")
			(hatch none 0.5)
			(connect_pads
				(clearance 0)
			)
			(min_thickness 0.25)
			(keepout
				(tracks allowed)
				(vias not_allowed)
				(pads allowed)
				(copperpour not_allowed)
				(footprints allowed)
			)
			(placement
				(enabled no)
				(sheetname "")
			)
			(fill
				(thermal_gap 0.5)
				(thermal_bridge_width 0.5)
				(island_removal_mode 0)
			)
			(polygon
				(pts
					(xy 378.714 -87.5665) (xy 378.206 -87.5665) (xy 378.206 -87.9475) (xy 378.714 -87.9475)
				)
			)
		)
	)
)
